# BASEBOARD_FAB2 (Tioga Pass) — schematic netlist excerpt (pin names and nets, part order shuffled) for the footprints in the layout excerpt that follows; sources: Cadence DE-HDL packaged netlist, KiCad conversion of Wiwynn_Tioga_Pass_MB.brd

R2U39  RES  665 1.0% CHIP  pkg 0402  page 167 : A = P3V3_STBY ; B = SMB_SENSOR_STBY_LVC3_SDA
C3M12  CAP  0.22UF 16V 10% X7R  pkg 0402  page 105 : A = P3E_CPU0_PE1_PCH_R_RXN<14> ; B = P3E_CPU0_PE1_PCH_RXN<14>
R2U20  RES  0.0 5% CHIP  pkg 0402  page 107 : A = P3E_CPU0_PE1_SS_RXP<3> ; B = P3E_CPU0_PE1_SS_R_RXP<3>

(kicad_pcb
	(version 20260206)
	(generator "pcbnew")
	(generator_version "10.0")
	(general
		(thickness 1.6)
		(legacy_teardrops no)
	)
	(paper "A4")
	(title_block
		(title "Wiwynn_Tioga_Pass_MB.brd")
		(comment 1 "Tioga Pass / footprints 4249-4251 of 4770")
	)
	(layers
		(0 "F.Cu" signal "TOP")
		(4 "In1.Cu" signal "L2GND")
		(6 "In2.Cu" signal "L3")
		(8 "In3.Cu" signal "L4GND")
		(10 "In4.Cu" signal "L5")
		(12 "In5.Cu" signal "L6GND")
		(14 "In6.Cu" signal "L7VCC")
		(16 "In7.Cu" signal "L8VCC")
		(18 "In8.Cu" signal "L9GND")
		(20 "In9.Cu" signal "L10")
		(22 "In10.Cu" signal "L11GND")
		(24 "In11.Cu" signal "L12")
		(26 "In12.Cu" signal "L13GND")
		(2 "B.Cu" signal "BOTTOM")
		(9 "F.Adhes" user "F.Adhesive")
		(11 "B.Adhes" user "B.Adhesive")
		(13 "F.Paste" user "Package Geometry/Pastemask Top")
		(15 "B.Paste" user "Package Geometry/Pastemask Bottom")
		(5 "F.SilkS" user "Ref Des/Silkscreen Top")
		(7 "B.SilkS" user "Ref Des/Silkscreen Bottom")
		(1 "F.Mask" user "Board Geometry/Soldermask Top")
		(3 "B.Mask" user "Board Geometry/Soldermask Bottom")
		(17 "Dwgs.User" user "User.Drawings")
		(19 "Cmts.User" user "User.Comments")
		(21 "Eco1.User" user "User.Eco1")
		(23 "Eco2.User" user "User.Eco2")
		(25 "Edge.Cuts" user "Board Geometry/Outline")
		(27 "Margin" user)
		(31 "F.CrtYd" user "Package Geometry/Place Bound Top")
		(29 "B.CrtYd" user "Package Geometry/Place Bound Bottom")
		(35 "F.Fab" user "Ref Des/Assembly Top")
		(33 "B.Fab" user "Ref Des/Assembly Bottom")
	)
	(footprint ""
		(layer "B.Cu")
		(at 341.728806 -60.368434)
		(property "Reference" "R2U20"
			(at 0 0 0)
			(layer "B.SilkS")
			(hide yes)
			(effects
				(font
					(size 1.27 1.27)
				)
				(justify mirror)
			)
		)
		(property "Value" ""
			(at 0 0 0)
			(layer "B.Fab")
			(effects
				(font
					(size 1.27 1.27)
				)
				(justify mirror)
			)
		)
		(duplicate_pad_numbers_are_jumpers no)
		(fp_poly
			(pts
				(xy 0.2794 -0.1016) (xy -0.2794 -0.1016) (xy -0.2794 0.9906) (xy 0.2794 0.9906)
			)
			(stroke
				(width 0)
				(type default)
			)
			(fill no)
			(layer "B.CrtYd")
		)
		(fp_line
			(start -0.2794 -0.1016)
			(end 0.2794 -0.1016)
			(stroke
				(width 0.1)
				(type default)
			)
			(layer "B.Fab")
		)
		(fp_line
			(start -0.2794 0.9906)
			(end -0.2794 -0.1016)
			(stroke
				(width 0.1)
				(type default)
			)
			(layer "B.Fab")
		)
		(fp_line
			(start 0.2794 -0.1016)
			(end 0.2794 0.9906)
			(stroke
				(width 0.1)
				(type default)
			)
			(layer "B.Fab")
		)
		(fp_line
			(start 0.2794 0.9906)
			(end -0.2794 0.9906)
			(stroke
				(width 0.1)
				(type default)
			)
			(layer "B.Fab")
		)
		(pad "1" smd rect
			(at 0 0 180)
			(size 0.508 0.508)
			(layers "B.Cu" "B.Mask" "B.Paste")
			(net "P3E_CPU0_PE1_SS_RXP<3>")
		)
		(pad "2" smd rect
			(at 0 0.889 180)
			(size 0.508 0.508)
			(layers "B.Cu" "B.Mask" "B.Paste")
			(net "P3E_CPU0_PE1_SS_R_RXP<3>")
		)
		(zone
			(layer "B.Cu")
			(hatch none 0.5)
			(connect_pads
				(clearance 0)
			)
			(min_thickness 0.25)
			(keepout
				(tracks allowed)
				(vias not_allowed)
				(pads allowed)
				(copperpour not_allowed)
				(footprints allowed)
			)
			(placement
				(enabled no)
				(sheetname "")
			)
			(fill
				(thermal_gap 0.5)
				(thermal_bridge_width 0.5)
				(island_removal_mode 0)
			)
			(polygon
				(pts
					(xy 341.982806 -60.114434) (xy 341.474806 -60.114434) (xy 341.474806 -59.733434) (xy 341.982806 -59.733434)
				)
			)
		)
		(zone
			(layer "B.Cu")
			(hatch none 0.5)
			(connect_pads
				(clearance 0)
			)
			(min_thickness 0.25)
			(keepout
				(tracks not_allowed)
				(vias allowed)
				(pads allowed)
				(copperpour not_allowed)
				(footprints allowed)
			)
			(placement
				(enabled no)
				(sheetname "")
			)
			(fill
				(thermal_gap 0.5)
				(thermal_bridge_width 0.5)
				(island_removal_mode 0)
			)
			(polygon
				(pts
					(xy 341.982806 -59.733434) (xy 341.474806 -59.733434) (xy 341.474806 -60.114434) (xy 341.982806 -60.114434)
				)
			)
		)
	)
	(footprint ""
		(layer "B.Cu")
		(at 350.022414 -125.227842 -90)
		(property "Reference" "C3M12"
			(at 0 0 90)
			(layer "B.SilkS")
			(hide yes)
			(effects
				(font
					(size 1.27 1.27)
				)
				(justify mirror)
			)
		)
		(property "Value" ""
			(at 0 0 90)
			(layer "B.Fab")
			(effects
				(font
					(size 1.27 1.27)
				)
				(justify mirror)
			)
		)
		(duplicate_pad_numbers_are_jumpers no)
		(fp_poly
			(pts
				(xy -0.3048 -0.1016) (xy -0.3048 0.9906) (xy 0.3048 0.9906) (xy 0.3048 -0.1016)
			)
			(stroke
				(width 0)
				(type default)
			)
			(fill no)
			(layer "B.CrtYd")
		)
		(fp_line
			(start -0.3048 0.9906)
			(end -0.3048 -0.1016)
			(stroke
				(width 0.1)
				(type default)
			)
			(layer "B.Fab")
		)
		(fp_line
			(start 0.3048 0.9906)
			(end -0.3048 0.9906)
			(stroke
				(width 0.1)
				(type default)
			)
			(layer "B.Fab")
		)
		(fp_line
			(start -0.3048 -0.1016)
			(end 0.3048 -0.1016)
			(stroke
				(width 0.1)
				(type default)
			)
			(layer "B.Fab")
		)
		(fp_line
			(start 0.3048 -0.1016)
			(end 0.3048 0.9906)
			(stroke
				(width 0.1)
				(type default)
			)
			(layer "B.Fab")
		)
		(pad "1" smd rect
			(at 0 0 90)
			(size 0.508 0.508)
			(layers "B.Cu" "B.Mask" "B.Paste")
			(net "P3E_CPU0_PE1_PCH_R_RXN<14>")
		)
		(pad "2" smd rect
			(at 0 0.889 90)
			(size 0.508 0.508)
			(layers "B.Cu" "B.Mask" "B.Paste")
			(net "P3E_CPU0_PE1_PCH_RXN<14>")
		)
		(zone
			(layer "B.Cu")
			(hatch none 0.5)
			(connect_pads
				(clearance 0)
			)
			(min_thickness 0.25)
			(keepout
				(tracks not_allowed)
				(vias allowed)
				(pads allowed)
				(copperpour not_allowed)
				(footprints allowed)
			)
			(placement
				(enabled no)
				(sheetname "")
			)
			(fill
				(thermal_gap 0.5)
				(thermal_bridge_width 0.5)
				(island_removal_mode 0)
			)
			(polygon
				(pts
					(xy 349.387414 -124.973842) (xy 349.387414 -125.481842) (xy 349.768414 -125.481842) (xy 349.768414 -124.973842)
				)
			)
		)
		(zone
			(layer "B.Cu")
			(hatch none 0.5)
			(connect_pads
				(clearance 0)
			)
			(min_thickness 0.25)
			(keepout
				(tracks allowed)
				(vias not_allowed)
				(pads allowed)
				(copperpour not_allowed)
				(footprints allowed)
			)
			(placement
				(enabled no)
				(sheetname "")
			)
			(fill
				(thermal_gap 0.5)
				(thermal_bridge_width 0.5)
				(island_removal_mode 0)
			)
			(polygon
				(pts
					(xy 349.768414 -124.973842) (xy 349.768414 -125.481842) (xy 349.387414 -125.481842) (xy 349.387414 -124.973842)
				)
			)
		)
	)
	(footprint ""
		(layer "B.Cu")
		(at 474.938344 -5.70992 90)
		(property "Reference" "R2U39"
			(at 0 0 90)
			(layer "B.SilkS")
			(hide yes)
			(effects
				(font
					(size 1.27 1.27)
				)
				(justify mirror)
			)
		)
		(property "Value" ""
			(at 0 0 90)
			(layer "B.Fab")
			(effects
				(font
					(size 1.27 1.27)
				)
				(justify mirror)
			)
		)
		(duplicate_pad_numbers_are_jumpers no)
		(fp_poly
			(pts
				(xy 0.2794 -0.1016) (xy -0.2794 -0.1016) (xy -0.2794 0.9906) (xy 0.2794 0.9906)
			)
			(stroke
				(width 0)
				(type default)
			)
			(fill no)
			(layer "B.CrtYd")
		)
		(fp_line
			(start 0.2794 -0.1016)
			(end 0.2794 0.9906)
			(stroke
				(width 0.1)
				(type default)
			)
			(layer "B.Fab")
		)
		(fp_line
			(start -0.2794 -0.1016)
			(end 0.2794 -0.1016)
			(stroke
				(width 0.1)
				(type default)
			)
			(layer "B.Fab")
		)
		(fp_line
			(start 0.2794 0.9906)
			(end -0.2794 0.9906)
			(stroke
				(width 0.1)
				(type default)
			)
			(layer "B.Fab")
		)
		(fp_line
			(start -0.2794 0.9906)
			(end -0.2794 -0.1016)
			(stroke
				(width 0.1)
				(type default)
			)
			(layer "B.Fab")
		)
		(pad "1" smd rect
			(at 0 0 270)
			(size 0.508 0.508)
			(layers "B.Cu" "B.Mask" "B.Paste")
			(net "P3V3_STBY")
		)
		(pad "2" smd rect
			(at 0 0.889 270)
			(size 0.508 0.508)
			(layers "B.Cu" "B.Mask" "B.Paste")
			(net "SMB_SENSOR_STBY_LVC3_SDA")
		)
		(zone
			(layer "B.Cu")
			(hatch none 0.5)
			(connect_pads
				(clearance 0)
			)
			(min_thickness 0.25)
			(keepout
				(tracks allowed)
				(vias not_allowed)
				(pads allowed)
				(copperpour not_allowed)
				(footprints allowed)
			)
			(placement
				(enabled no)
				(sheetname "")
			)
			(fill
				(thermal_gap 0.5)
				(thermal_bridge_width 0.5)
				(island_removal_mode 0)
			)
			(polygon
				(pts
					(xy 475.192344 -5.96392) (xy 475.192344 -5.45592) (xy 475.573344 -5.45592) (xy 475.573344 -5.96392)
				)
			)
		)
		(zone
			(layer "B.Cu")
			(hatch none 0.5)
			(connect_pads
				(clearance 0)
			)
			(min_thickness 0.25)
			(keepout
				(tracks not_allowed)
				(vias allowed)
				(pads allowed)
				(copperpour not_allowed)
				(footprints allowed)
			)
			(placement
				(enabled no)
				(sheetname "")
			)
			(fill
				(thermal_gap 0.5)
				(thermal_bridge_width 0.5)
				(island_removal_mode 0)
			)
			(polygon
				(pts
					(xy 475.573344 -5.96392) (xy 475.573344 -5.45592) (xy 475.192344 -5.45592) (xy 475.192344 -5.96392)
				)
			)
		)
	)
)
